(kicad_pcb
	(version 20241229)
	(generator "pcbnew")
	(generator_version "9.0")
	(general
		(thickness 1.552)
		(legacy_teardrops no)
	)
	(paper "A4")
	(title_block
		(date "2023-07-25")
		(rev "1.1.4")
		(comment 9 "footprints 105-109 of 379")
	)
	(layers
		(0 "F.Cu" signal)
		(4 "In1.Cu" signal)
		(6 "In2.Cu" signal)
		(8 "In3.Cu" signal)
		(10 "In4.Cu" signal)
		(12 "In5.Cu" signal)
		(14 "In6.Cu" signal)
		(2 "B.Cu" signal)
		(9 "F.Adhes" user "F.Adhesive")
		(11 "B.Adhes" user "B.Adhesive")
		(13 "F.Paste" user)
		(15 "B.Paste" user)
		(5 "F.SilkS" user "F.Silkscreen")
		(7 "B.SilkS" user "B.Silkscreen")
		(1 "F.Mask" user)
		(3 "B.Mask" user)
		(17 "Dwgs.User" user "User.Drawings")
		(19 "Cmts.User" user "User.Comments")
		(21 "Eco1.User" user "User.Eco1")
		(23 "Eco2.User" user "User.Eco2")
		(25 "Edge.Cuts" user)
		(27 "Margin" user)
		(31 "F.CrtYd" user "F.Courtyard")
		(29 "B.CrtYd" user "B.Courtyard")
		(35 "F.Fab" user)
		(33 "B.Fab" user)
	)
	(footprint "antmicro-footprints:R_0402_1005Metric"
		(layer "F.Cu")
		(at 84.2 106.15)
		(descr "Resistor SMD 0402")
		(tags "resistor SMD 0402")
		(property "Reference" "R59"
			(at 2.13 -7.91 0)
			(layer "F.SilkS")
			(effects
				(font
					(size 0.65 0.65)
					(thickness 0.15)
				)
				(justify left bottom)
			)
		)
		(property "Value" "R_75R_0402"
			(at 0 1.4 0)
			(layer "F.Fab")
			(hide yes)
			(effects
				(font
					(size 0.7 0.7)
					(thickness 0.15)
				)
				(justify left bottom)
			)
		)
		(property "Datasheet" "https://www.bourns.com/docs/product-datasheets/cr.pdf"
			(at 0 0 0)
			(layer "F.Fab")
			(hide yes)
			(effects
				(font
					(size 1.27 1.27)
					(thickness 0.15)
				)
			)
		)
		(property "Description" "SMD Chip Resistor, 75 ohm, ± 1%, 62.5 mW, 0402 [1005 Metric], Thick Film, General Purpose"
			(at 0 0 0)
			(layer "F.Fab")
			(hide yes)
			(effects
				(font
					(size 1.27 1.27)
					(thickness 0.15)
				)
			)
		)
		(property "Author" "Antmicro"
			(at 0 0 0)
			(layer "F.Fab")
			(hide yes)
			(effects
				(font
					(size 1 1)
					(thickness 0.15)
				)
			)
		)
		(property "License" "Apache-2.0"
			(at 0 0 0)
			(layer "F.Fab")
			(hide yes)
			(effects
				(font
					(size 1 1)
					(thickness 0.15)
				)
			)
		)
		(property "MPN" "CR0402-FX-75R0GLF"
			(at 0 0 0)
			(layer "F.Fab")
			(hide yes)
			(effects
				(font
					(size 1 1)
					(thickness 0.15)
				)
			)
		)
		(property "Manufacturer" "Bourns"
			(at 0 0 0)
			(layer "F.Fab")
			(hide yes)
			(effects
				(font
					(size 1 1)
					(thickness 0.15)
				)
			)
		)
		(property "Tolerance" "1%"
			(at 0 0 0)
			(layer "F.Fab")
			(hide yes)
			(effects
				(font
					(size 1 1)
					(thickness 0.15)
				)
			)
		)
		(property "Val" "75R"
			(at 0 0 0)
			(layer "F.Fab")
			(hide yes)
			(effects
				(font
					(size 1 1)
					(thickness 0.15)
				)
			)
		)
		(sheetname "/SDI/")
		(sheetfile "sdi.kicad_sch")
		(attr smd)
		(fp_rect
			(start -0.925 -0.47)
			(end 0.925 0.47)
			(stroke
				(width 0.05)
				(type default)
			)
			(fill no)
			(layer "F.CrtYd")
		)
		(fp_rect
			(start -0.5 -0.25)
			(end 0.5 0.25)
			(stroke
				(width 0.15)
				(type solid)
			)
			(fill no)
			(layer "F.Fab")
		)
		(fp_text user "Author: Antmicro"
			(at -0.95 4.169 0)
			(layer "F.Fab")
			(effects
				(font
					(size 0.7 0.7)
					(thickness 0.15)
				)
				(justify left bottom)
			)
		)
		(fp_text user "License: Apache-2.0"
			(at -0.95 5.169 0)
			(layer "F.Fab")
			(effects
				(font
					(size 0.7 0.7)
					(thickness 0.15)
				)
				(justify left bottom)
			)
		)
		(fp_text user "${REFERENCE}"
			(at -0.95 3.168 0)
			(layer "F.Fab")
			(effects
				(font
					(size 0.7 0.7)
					(thickness 0.15)
				)
				(justify left bottom)
			)
		)
		(pad "1" smd roundrect
			(at -0.48 0)
			(size 0.59 0.64)
			(layers "F.Cu" "F.Mask" "F.Paste")
			(roundrect_rratio 0.25)
			(net 2 "+3V3")
			(pintype "passive")
		)
		(pad "2" smd roundrect
			(at 0.48 0)
			(size 0.59 0.64)
			(layers "F.Cu" "F.Mask" "F.Paste")
			(roundrect_rratio 0.25)
			(net 254 "/SDI/SDI_OUT_N")
			(pintype "passive")
		)
	)
	(footprint "antmicro-footprints:C_0603_1608Metric"
		(layer "F.Cu")
		(at 138.19 110.9)
		(descr "Capacitor SMD 0603")
		(tags "capacitor 0603")
		(property "Reference" "C31"
			(at -3.36 0.24 0)
			(layer "F.SilkS")
			(effects
				(font
					(size 0.65 0.65)
					(thickness 0.15)
				)
				(justify left bottom)
			)
		)
		(property "Value" "C_10u_0603"
			(at 0 1.6 0)
			(layer "F.Fab")
			(hide yes)
			(effects
				(font
					(size 0.7 0.7)
					(thickness 0.15)
				)
				(justify left bottom)
			)
		)
		(property "Datasheet" "https://www.murata.com/products/productdetail?partno=GRM188R61A106KE69%23"
			(at 0 0 0)
			(layer "F.Fab")
			(hide yes)
			(effects
				(font
					(size 1.27 1.27)
					(thickness 0.15)
				)
			)
		)
		(property "Description" "SMD Multilayer Ceramic Capacitor, 10 µF, 10 V, 0603 [1608 Metric], ± 10%, X5R, GRM Series"
			(at 0 0 0)
			(layer "F.Fab")
			(hide yes)
			(effects
				(font
					(size 1.27 1.27)
					(thickness 0.15)
				)
			)
		)
		(property "Author" "Antmicro"
			(at 0 0 0)
			(layer "F.Fab")
			(hide yes)
			(effects
				(font
					(size 1 1)
					(thickness 0.15)
				)
			)
		)
		(property "License" "Apache-2.0"
			(at 0 0 0)
			(layer "F.Fab")
			(hide yes)
			(effects
				(font
					(size 1 1)
					(thickness 0.15)
				)
			)
		)
		(property "MPN" "GRM188R61A106KE69D"
			(at 0 0 0)
			(layer "F.Fab")
			(hide yes)
			(effects
				(font
					(size 1 1)
					(thickness 0.15)
				)
			)
		)
		(property "Manufacturer" "Murata"
			(at 0 0 0)
			(layer "F.Fab")
			(hide yes)
			(effects
				(font
					(size 1 1)
					(thickness 0.15)
				)
			)
		)
		(property "Val" "10u"
			(at 0 0 0)
			(layer "F.Fab")
			(hide yes)
			(effects
				(font
					(size 1 1)
					(thickness 0.15)
				)
			)
		)
		(property "Voltage" ""
			(at 0 0 0)
			(layer "F.Fab")
			(hide yes)
			(effects
				(font
					(size 1 1)
					(thickness 0.15)
				)
			)
		)
		(property "Dielectric" "template_dielectric"
			(at 0 0 0)
			(unlocked yes)
			(layer "F.Fab")
			(hide yes)
			(effects
				(font
					(size 1 1)
					(thickness 0.15)
				)
			)
		)
		(sheetname "/Power Supply/")
		(sheetfile "supply.kicad_sch")
		(attr smd)
		(fp_line
			(start -0.15 -0.4)
			(end 0.15 -0.4)
			(stroke
				(width 0.15)
				(type solid)
			)
			(layer "F.SilkS")
		)
		(fp_line
			(start -0.15 0.4)
			(end 0.15 0.4)
			(stroke
				(width 0.15)
				(type solid)
			)
			(layer "F.SilkS")
		)
		(fp_rect
			(start -1.25 -0.65)
			(end 1.25 0.65)
			(stroke
				(width 0.05)
				(type solid)
			)
			(fill no)
			(layer "F.CrtYd")
		)
		(fp_rect
			(start -0.8 -0.4)
			(end 0.8 0.4)
			(stroke
				(width 0.15)
				(type solid)
			)
			(fill no)
			(layer "F.Fab")
		)
		(fp_text user "${REFERENCE}"
			(at -1.682 3.895 0)
			(layer "F.Fab")
			(effects
				(font
					(size 0.7 0.7)
					(thickness 0.15)
				)
				(justify left bottom)
			)
		)
		(fp_text user "Author: Antmicro"
			(at -1.682 4.894 0)
			(layer "F.Fab")
			(effects
				(font
					(size 0.7 0.7)
					(thickness 0.15)
				)
				(justify left bottom)
			)
		)
		(fp_text user "License: Apache-2.0"
			(at -1.682 5.895 0)
			(layer "F.Fab")
			(effects
				(font
					(size 0.7 0.7)
					(thickness 0.15)
				)
				(justify left bottom)
			)
		)
		(pad "1" smd roundrect
			(at -0.7 0)
			(size 0.8 1)
			(layers "F.Cu" "F.Mask" "F.Paste")
			(roundrect_rratio 0.2)
			(net 1 "GND")
			(pintype "passive")
		)
		(pad "2" smd roundrect
			(at 0.7 0)
			(size 0.8 1)
			(layers "F.Cu" "F.Mask" "F.Paste")
			(roundrect_rratio 0.2)
			(net 50 "+1V8")
			(pintype "passive")
		)
	)
	(footprint "antmicro-footprints:C_0402_1005Metric"
		(layer "F.Cu")
		(at 133.83 112.15)
		(descr "Capacitor SMD 0402")
		(tags "capacitor SMD 0402")
		(property "Reference" "C80"
			(at -3.2 -0.01 0)
			(layer "F.SilkS")
			(effects
				(font
					(size 0.65 0.65)
					(thickness 0.15)
				)
				(justify left bottom)
			)
		)
		(property "Value" "C_100n_0402"
			(at 0 1.4 0)
			(layer "F.Fab")
			(hide yes)
			(effects
				(font
					(size 0.7 0.7)
					(thickness 0.15)
				)
				(justify left bottom)
			)
		)
		(property "Datasheet" "https://www.murata.com/products/productdetail?partno=GRM155R61H104KE14%23"
			(at 0 0 0)
			(layer "F.Fab")
			(hide yes)
			(effects
				(font
					(size 1.27 1.27)
					(thickness 0.15)
				)
			)
		)
		(property "Description" "SMD Multilayer Ceramic Capacitor, 0.1 µF, 50 V, 0402 [1005 Metric], ± 10%, X5R, GRM Series"
			(at 0 0 0)
			(layer "F.Fab")
			(hide yes)
			(effects
				(font
					(size 1.27 1.27)
					(thickness 0.15)
				)
			)
		)
		(property "Author" "Antmicro"
			(at 0 0 0)
			(layer "F.Fab")
			(hide yes)
			(effects
				(font
					(size 1 1)
					(thickness 0.15)
				)
			)
		)
		(property "Dielectric" "X5R"
			(at 0 0 0)
			(layer "F.Fab")
			(hide yes)
			(effects
				(font
					(size 1 1)
					(thickness 0.15)
				)
			)
		)
		(property "License" "Apache-2.0"
			(at 0 0 0)
			(layer "F.Fab")
			(hide yes)
			(effects
				(font
					(size 1 1)
					(thickness 0.15)
				)
			)
		)
		(property "MPN" "GRM155R61H104KE14D"
			(at 0 0 0)
			(layer "F.Fab")
			(hide yes)
			(effects
				(font
					(size 1 1)
					(thickness 0.15)
				)
			)
		)
		(property "Manufacturer" "Murata"
			(at 0 0 0)
			(layer "F.Fab")
			(hide yes)
			(effects
				(font
					(size 1 1)
					(thickness 0.15)
				)
			)
		)
		(property "Val" "100n"
			(at 0 0 0)
			(layer "F.Fab")
			(hide yes)
			(effects
				(font
					(size 1 1)
					(thickness 0.15)
				)
			)
		)
		(property "Voltage" "50V"
			(at 0 0 0)
			(layer "F.Fab")
			(hide yes)
			(effects
				(font
					(size 1 1)
					(thickness 0.15)
				)
			)
		)
		(sheetname "/FPGA/")
		(sheetfile "fpga.kicad_sch")
		(attr smd)
		(fp_rect
			(start -0.925 -0.47)
			(end 0.925 0.47)
			(stroke
				(width 0.05)
				(type default)
			)
			(fill no)
			(layer "F.CrtYd")
		)
		(fp_line
			(start -0.494 -0.25)
			(end 0.504 -0.25)
			(stroke
				(width 0.15)
				(type solid)
			)
			(layer "F.Fab")
		)
		(fp_line
			(start -0.494 0.248)
			(end -0.494 -0.25)
			(stroke
				(width 0.15)
				(type solid)
			)
			(layer "F.Fab")
		)
		(fp_line
			(start 0.504 -0.25)
			(end 0.504 0.248)
			(stroke
				(width 0.15)
				(type solid)
			)
			(layer "F.Fab")
		)
		(fp_line
			(start 0.504 0.248)
			(end -0.494 0.248)
			(stroke
				(width 0.15)
				(type solid)
			)
			(layer "F.Fab")
		)
		(fp_text user "License: Apache-2.0"
			(at -0.939 5.799 0)
			(layer "F.Fab")
			(effects
				(font
					(size 0.7 0.7)
					(thickness 0.15)
				)
				(justify left bottom)
			)
		)
		(fp_text user "Author: Antmicro"
			(at -0.939 3.399 0)
			(layer "F.Fab")
			(effects
				(font
					(size 0.7 0.7)
					(thickness 0.15)
				)
				(justify left bottom)
			)
		)
		(fp_text user "${REFERENCE}"
			(at -0.939 4.599 0)
			(layer "F.Fab")
			(effects
				(font
					(size 0.7 0.7)
					(thickness 0.15)
				)
				(justify left bottom)
			)
		)
		(pad "1" smd roundrect
			(at -0.48 0)
			(size 0.59 0.64)
			(layers "F.Cu" "F.Mask" "F.Paste")
			(roundrect_rratio 0.25)
			(net 1 "GND")
			(pintype "passive")
		)
		(pad "2" smd roundrect
			(at 0.48 0)
			(size 0.59 0.64)
			(layers "F.Cu" "F.Mask" "F.Paste")
			(roundrect_rratio 0.25)
			(net 381 "Net-(C80-Pad2)")
			(pintype "passive")
		)
	)
	(footprint "antmicro-footprints:R_0402_1005Metric"
		(layer "F.Cu")
		(at 89.97 109.55 -90)
		(descr "Resistor SMD 0402")
		(tags "resistor SMD 0402")
		(property "Reference" "R38"
			(at -1.11 -1.46 90)
			(layer "F.SilkS")
			(effects
				(font
					(size 0.65 0.65)
					(thickness 0.15)
				)
				(justify right bottom)
			)
		)
		(property "Value" "R_0R_0402"
			(at 0 1.4 90)
			(layer "F.Fab")
			(hide yes)
			(effects
				(font
					(size 0.7 0.7)
					(thickness 0.15)
				)
				(justify right bottom)
			)
		)
		(property "Datasheet" "https://industrial.panasonic.com/cdbs/www-data/pdf/RDA0000/AOA0000C301.pdf"
			(at 0 0 270)
			(layer "F.Fab")
			(hide yes)
			(effects
				(font
					(size 1.27 1.27)
					(thickness 0.15)
				)
			)
		)
		(property "Description" "SMD Chip Resistor, Jumper, 0 ohm, 100 mW, 0402 [1005 Metric], Thick Film, General Purpose"
			(at 0 0 270)
			(layer "F.Fab")
			(hide yes)
			(effects
				(font
					(size 1.27 1.27)
					(thickness 0.15)
				)
			)
		)
		(property "Author" "Antmicro"
			(at -19.58 199.52 0)
			(layer "F.Fab")
			(hide yes)
			(effects
				(font
					(size 1 1)
					(thickness 0.15)
				)
			)
		)
		(property "Current" "1A"
			(at -19.58 199.52 0)
			(layer "F.Fab")
			(hide yes)
			(effects
				(font
					(size 1 1)
					(thickness 0.15)
				)
			)
		)
		(property "License" "Apache-2.0"
			(at -19.58 199.52 0)
			(layer "F.Fab")
			(hide yes)
			(effects
				(font
					(size 1 1)
					(thickness 0.15)
				)
			)
		)
		(property "MPN" "ERJ2GE0R00X"
			(at -19.58 199.52 0)
			(layer "F.Fab")
			(hide yes)
			(effects
				(font
					(size 1 1)
					(thickness 0.15)
				)
			)
		)
		(property "Manufacturer" "Panasonic"
			(at -19.58 199.52 0)
			(layer "F.Fab")
			(hide yes)
			(effects
				(font
					(size 1 1)
					(thickness 0.15)
				)
			)
		)
		(property "Tolerance" "~"
			(at -19.58 199.52 0)
			(layer "F.Fab")
			(hide yes)
			(effects
				(font
					(size 1 1)
					(thickness 0.15)
				)
			)
		)
		(property "Val" "0R"
			(at -19.58 199.52 0)
			(layer "F.Fab")
			(hide yes)
			(effects
				(font
					(size 1 1)
					(thickness 0.15)
				)
			)
		)
		(sheetname "/SDI/")
		(sheetfile "sdi.kicad_sch")
		(attr smd)
		(fp_rect
			(start -0.925 -0.47)
			(end 0.925 0.47)
			(stroke
				(width 0.05)
				(type default)
			)
			(fill no)
			(layer "F.CrtYd")
		)
		(fp_rect
			(start -0.5 -0.25)
			(end 0.5 0.25)
			(stroke
				(width 0.15)
				(type solid)
			)
			(fill no)
			(layer "F.Fab")
		)
		(fp_text user "${REFERENCE}"
			(at -0.95 3.168 270)
			(layer "F.Fab")
			(effects
				(font
					(size 0.7 0.7)
					(thickness 0.15)
				)
				(justify left bottom)
			)
		)
		(fp_text user "Author: Antmicro"
			(at -0.95 4.169 270)
			(layer "F.Fab")
			(effects
				(font
					(size 0.7 0.7)
					(thickness 0.15)
				)
				(justify left bottom)
			)
		)
		(fp_text user "License: Apache-2.0"
			(at -0.95 5.169 270)
			(layer "F.Fab")
			(effects
				(font
					(size 0.7 0.7)
					(thickness 0.15)
				)
				(justify left bottom)
			)
		)
		(pad "1" smd roundrect
			(at -0.48 0 270)
			(size 0.59 0.64)
			(layers "F.Cu" "F.Mask" "F.Paste")
			(roundrect_rratio 0.25)
			(net 285 "Net-(U16-~{EQ_EN})")
			(pintype "passive")
		)
		(pad "2" smd roundrect
			(at 0.48 0 270)
			(size 0.59 0.64)
			(layers "F.Cu" "F.Mask" "F.Paste")
			(roundrect_rratio 0.25)
			(net 2 "+3V3")
			(pintype "passive")
		)
	)
	(footprint "antmicro-footprints:R_0603_1608Metric"
		(layer "F.Cu")
		(at 104.59 107.2 -90)
		(descr "Resistor SMD 0603")
		(tags "resistor SMD 0603")
		(property "Reference" "R65"
			(at 1.24 -0.44 90)
			(layer "F.SilkS")
			(effects
				(font
					(size 0.65 0.65)
					(thickness 0.15)
				)
				(justify right bottom)
			)
		)
		(property "Value" "R_0R_0603"
			(at 0 1.6 90)
			(layer "F.Fab")
			(hide yes)
			(effects
				(font
					(size 0.7 0.7)
					(thickness 0.15)
				)
				(justify right bottom)
			)
		)
		(property "Datasheet" "https://www.bourns.com/docs/product-datasheets/cr.pdf?sfvrsn=574d41f6_14"
			(at 0 0 270)
			(layer "F.Fab")
			(hide yes)
			(effects
				(font
					(size 1.27 1.27)
					(thickness 0.15)
				)
			)
		)
		(property "Description" "Zero Ohm Resistor, Jumper, 0603 [1608 Metric], Thick Film, 100 mW, 1 A, Surface Mount Device, CR"
			(at 0 0 270)
			(layer "F.Fab")
			(hide yes)
			(effects
				(font
					(size 1.27 1.27)
					(thickness 0.15)
				)
			)
		)
		(property "Author" "Antmicro"
			(at -2.61 211.79 0)
			(layer "F.Fab")
			(hide yes)
			(effects
				(font
					(size 1 1)
					(thickness 0.15)
				)
			)
		)
		(property "Current" "1A"
			(at -2.61 211.79 0)
			(layer "F.Fab")
			(hide yes)
			(effects
				(font
					(size 1 1)
					(thickness 0.15)
				)
			)
		)
		(property "License" "Apache-2.0"
			(at -2.61 211.79 0)
			(layer "F.Fab")
			(hide yes)
			(effects
				(font
					(size 1 1)
					(thickness 0.15)
				)
			)
		)
		(property "MPN" "CR0603-J/-000ELF"
			(at -2.61 211.79 0)
			(layer "F.Fab")
			(hide yes)
			(effects
				(font
					(size 1 1)
					(thickness 0.15)
				)
			)
		)
		(property "Manufacturer" "Bourns"
			(at -2.61 211.79 0)
			(layer "F.Fab")
			(hide yes)
			(effects
				(font
					(size 1 1)
					(thickness 0.15)
				)
			)
		)
		(property "Tolerance" "~"
			(at -2.61 211.79 0)
			(layer "F.Fab")
			(hide yes)
			(effects
				(font
					(size 1 1)
					(thickness 0.15)
				)
			)
		)
		(property "Val" "0R"
			(at -2.61 211.79 0)
			(layer "F.Fab")
			(hide yes)
			(effects
				(font
					(size 1 1)
					(thickness 0.15)
				)
			)
		)
		(sheetname "/FPGA/")
		(sheetfile "fpga.kicad_sch")
		(attr smd)
		(fp_line
			(start -0.15 0.4)
			(end 0.15 0.4)
			(stroke
				(width 0.15)
				(type solid)
			)
			(layer "F.SilkS")
		)
		(fp_line
			(start -0.15 -0.4)
			(end 0.15 -0.4)
			(stroke
				(width 0.15)
				(type solid)
			)
			(layer "F.SilkS")
		)
		(fp_rect
			(start -1.25 -0.65)
			(end 1.25 0.65)
			(stroke
				(width 0.05)
				(type solid)
			)
			(fill no)
			(layer "F.CrtYd")
		)
		(fp_rect
			(start -0.8 -0.4)
			(end 0.8 0.4)
			(stroke
				(width 0.15)
				(type solid)
			)
			(fill no)
			(layer "F.Fab")
		)
		(fp_text user "${REFERENCE}"
			(at -1.25 3.898 270)
			(layer "F.Fab")
			(effects
				(font
					(size 0.7 0.7)
					(thickness 0.15)
				)
				(justify left bottom)
			)
		)
		(fp_text user "License: Apache-2.0"
			(at -1.25 5.9 270)
			(layer "F.Fab")
			(effects
				(font
					(size 0.7 0.7)
					(thickness 0.15)
				)
				(justify left bottom)
			)
		)
		(fp_text user "Author: Antmicro"
			(at -1.25 4.9 270)
			(layer "F.Fab")
			(effects
				(font
					(size 0.7 0.7)
					(thickness 0.15)
				)
				(justify left bottom)
			)
		)
		(pad "1" smd roundrect
			(at -0.7 0 270)
			(size 0.8 1)
			(layers "F.Cu" "F.Mask" "F.Paste")
			(roundrect_rratio 0.2)
			(net 298 "Net-(U17-SCL)")
			(pintype "passive")
		)
		(pad "2" smd roundrect
			(at 0.7 0 270)
			(size 0.8 1)
			(layers "F.Cu" "F.Mask" "F.Paste")
			(roundrect_rratio 0.2)
			(net 100 "SCL")
			(pintype "passive")
		)
	)
)
